# S9S_MB_2U (Grand Teton) — schematic netlist excerpt (pin names and nets, part order shuffled) for the footprints in the layout excerpt that follows; sources: Cadence DE-HDL packaged netlist, KiCad conversion of 03242023_DA0F0TMBIJ0_F0T_Motherboard_J_brd_V01_OCP.brd

PR4001  Q_RES  6.8K 1% EMPTY  pkg 0402LF  page 242 : A = P12V_SCM_UV ; B = P12V_SCM_OV
C971  Q_CAP  10UF 6.3V 20% X6S  pkg C0402  page 74 : A = PVCCIN_CPU0 ; B = GND

(kicad_pcb
	(version 20260206)
	(generator "pcbnew")
	(generator_version "10.0")
	(general
		(thickness 1.6)
		(legacy_teardrops no)
	)
	(paper "A4")
	(title_block
		(title "03242023_DA0F0TMBIJ0_F0T_Motherboard_J_brd_V01_OCP.brd")
		(comment 1 "Grand Teton / footprints 2556-2557 of 6105")
	)
	(layers
		(0 "F.Cu" signal "TOP")
		(4 "In1.Cu" signal "GND")
		(6 "In2.Cu" signal "IN1")
		(8 "In3.Cu" signal "GND1")
		(10 "In4.Cu" signal "IN2")
		(12 "In5.Cu" signal "GND2")
		(14 "In6.Cu" signal "IN3")
		(16 "In7.Cu" signal "GND3")
		(18 "In8.Cu" signal "VCC")
		(20 "In9.Cu" signal "VCC1")
		(22 "In10.Cu" signal "GND4")
		(24 "In11.Cu" signal "IN4")
		(26 "In12.Cu" signal "GND5")
		(28 "In13.Cu" signal "IN5")
		(30 "In14.Cu" signal "GND6")
		(32 "In15.Cu" signal "IN6")
		(34 "In16.Cu" signal "GND7")
		(2 "B.Cu" signal "BOTTOM")
		(9 "F.Adhes" user "F.Adhesive")
		(11 "B.Adhes" user "B.Adhesive")
		(13 "F.Paste" user "Package Geometry/Pastemask Top")
		(15 "B.Paste" user "Package Geometry/Pastemask Bottom")
		(5 "F.SilkS" user "Ref Des/Silkscreen Top")
		(7 "B.SilkS" user "Ref Des/Silkscreen Bottom")
		(1 "F.Mask" user "Board Geometry/Soldermask Top")
		(3 "B.Mask" user "Board Geometry/Soldermask Bottom")
		(17 "Dwgs.User" user "User.Drawings")
		(19 "Cmts.User" user "User.Comments")
		(21 "Eco1.User" user "User.Eco1")
		(23 "Eco2.User" user "User.Eco2")
		(25 "Edge.Cuts" user "Board Geometry/Outline")
		(27 "Margin" user)
		(31 "F.CrtYd" user "Package Geometry/Place Bound Top")
		(29 "B.CrtYd" user "Package Geometry/Place Bound Bottom")
		(35 "F.Fab" user "Ref Des/Assembly Top")
		(33 "B.Fab" user "Ref Des/Assembly Bottom")
	)
	(footprint ""
		(layer "F.Cu")
		(at 187.221622 -22.727158 -90)
		(property "Reference" "PR4001"
			(at 0 0 270)
			(layer "F.SilkS")
			(hide yes)
			(effects
				(font
					(size 1.27 1.27)
				)
			)
		)
		(property "Value" ""
			(at 0 0 270)
			(layer "F.Fab")
			(effects
				(font
					(size 1.27 1.27)
				)
			)
		)
		(duplicate_pad_numbers_are_jumpers no)
		(fp_line
			(start -0.7874 0.4064)
			(end -0.7874 -0.4064)
			(stroke
				(width 0.1524)
				(type default)
			)
			(layer "F.SilkS")
		)
		(fp_line
			(start 0.7874 0.4064)
			(end -0.7874 0.4064)
			(stroke
				(width 0.1524)
				(type default)
			)
			(layer "F.SilkS")
		)
		(fp_line
			(start -0.7874 -0.4064)
			(end 0.7874 -0.4064)
			(stroke
				(width 0.1524)
				(type default)
			)
			(layer "F.SilkS")
		)
		(fp_line
			(start 0.7874 -0.4064)
			(end 0.7874 0.4064)
			(stroke
				(width 0.1524)
				(type default)
			)
			(layer "F.SilkS")
		)
		(fp_line
			(start -0.67945 0.3048)
			(end -0.67945 -0.305054)
			(stroke
				(width 0.1)
				(type default)
			)
			(layer "F.Fab")
		)
		(fp_line
			(start -0.12065 0.3048)
			(end -0.67945 0.3048)
			(stroke
				(width 0.1)
				(type default)
			)
			(layer "F.Fab")
		)
		(fp_line
			(start 0.120396 0.3048)
			(end 0.120396 0.2794)
			(stroke
				(width 0.1)
				(type default)
			)
			(layer "F.Fab")
		)
		(fp_line
			(start 0.67945 0.3048)
			(end 0.120396 0.3048)
			(stroke
				(width 0.1)
				(type default)
			)
			(layer "F.Fab")
		)
		(fp_line
			(start -0.12065 0.2794)
			(end -0.12065 0.3048)
			(stroke
				(width 0.1)
				(type default)
			)
			(layer "F.Fab")
		)
		(fp_line
			(start 0.120396 0.2794)
			(end -0.12065 0.2794)
			(stroke
				(width 0.1)
				(type default)
			)
			(layer "F.Fab")
		)
		(fp_line
			(start -0.12065 -0.2794)
			(end 0.12065 -0.2794)
			(stroke
				(width 0.1)
				(type default)
			)
			(layer "F.Fab")
		)
		(fp_line
			(start 0.12065 -0.2794)
			(end 0.12065 -0.3048)
			(stroke
				(width 0.1)
				(type default)
			)
			(layer "F.Fab")
		)
		(fp_line
			(start 0.12065 -0.3048)
			(end 0.67945 -0.3048)
			(stroke
				(width 0.1)
				(type default)
			)
			(layer "F.Fab")
		)
		(fp_line
			(start 0.67945 -0.3048)
			(end 0.67945 0.3048)
			(stroke
				(width 0.1)
				(type default)
			)
			(layer "F.Fab")
		)
		(fp_line
			(start -0.67945 -0.305054)
			(end -0.12065 -0.305054)
			(stroke
				(width 0.1)
				(type default)
			)
			(layer "F.Fab")
		)
		(fp_line
			(start -0.12065 -0.305054)
			(end -0.12065 -0.2794)
			(stroke
				(width 0.1)
				(type default)
			)
			(layer "F.Fab")
		)
		(pad "1" smd circle
			(at -0.40005 0 270)
			(size 0 0)
			(layers "F.Cu" "F.Mask" "F.Paste")
			(net "P12V_SCM_UV")
		)
		(pad "2" smd circle
			(at 0.40005 0 270)
			(size 0 0)
			(layers "F.Cu" "F.Mask" "F.Paste")
			(net "P12V_SCM_OV")
		)
	)
	(footprint ""
		(layer "F.Cu")
		(at 353.266248 -247.715024 90)
		(property "Reference" "C971"
			(at 0 0 90)
			(layer "F.SilkS")
			(hide yes)
			(effects
				(font
					(size 1.27 1.27)
				)
			)
		)
		(property "Value" ""
			(at 0 0 90)
			(layer "F.Fab")
			(effects
				(font
					(size 1.27 1.27)
				)
			)
		)
		(duplicate_pad_numbers_are_jumpers no)
		(fp_line
			(start 0.7874 -0.4064)
			(end 0.7874 0.4064)
			(stroke
				(width 0.1524)
				(type default)
			)
			(layer "F.SilkS")
		)
		(fp_line
			(start -0.7874 -0.4064)
			(end 0.7874 -0.4064)
			(stroke
				(width 0.1524)
				(type default)
			)
			(layer "F.SilkS")
		)
		(fp_line
			(start 0.7874 0.4064)
			(end -0.7874 0.4064)
			(stroke
				(width 0.1524)
				(type default)
			)
			(layer "F.SilkS")
		)
		(fp_line
			(start -0.7874 0.4064)
			(end -0.7874 -0.4064)
			(stroke
				(width 0.1524)
				(type default)
			)
			(layer "F.SilkS")
		)
		(fp_line
			(start -0.12065 -0.305054)
			(end -0.12065 -0.2794)
			(stroke
				(width 0.1)
				(type default)
			)
			(layer "F.Fab")
		)
		(fp_line
			(start -0.67945 -0.305054)
			(end -0.12065 -0.305054)
			(stroke
				(width 0.1)
				(type default)
			)
			(layer "F.Fab")
		)
		(fp_line
			(start 0.67945 -0.3048)
			(end 0.67945 0.3048)
			(stroke
				(width 0.1)
				(type default)
			)
			(layer "F.Fab")
		)
		(fp_line
			(start 0.12065 -0.3048)
			(end 0.67945 -0.3048)
			(stroke
				(width 0.1)
				(type default)
			)
			(layer "F.Fab")
		)
		(fp_line
			(start 0.12065 -0.2794)
			(end 0.12065 -0.3048)
			(stroke
				(width 0.1)
				(type default)
			)
			(layer "F.Fab")
		)
		(fp_line
			(start -0.12065 -0.2794)
			(end 0.12065 -0.2794)
			(stroke
				(width 0.1)
				(type default)
			)
			(layer "F.Fab")
		)
		(fp_line
			(start 0.120396 0.2794)
			(end -0.12065 0.2794)
			(stroke
				(width 0.1)
				(type default)
			)
			(layer "F.Fab")
		)
		(fp_line
			(start -0.12065 0.2794)
			(end -0.12065 0.3048)
			(stroke
				(width 0.1)
				(type default)
			)
			(layer "F.Fab")
		)
		(fp_line
			(start 0.67945 0.3048)
			(end 0.120396 0.3048)
			(stroke
				(width 0.1)
				(type default)
			)
			(layer "F.Fab")
		)
		(fp_line
			(start 0.120396 0.3048)
			(end 0.120396 0.2794)
			(stroke
				(width 0.1)
				(type default)
			)
			(layer "F.Fab")
		)
		(fp_line
			(start -0.12065 0.3048)
			(end -0.67945 0.3048)
			(stroke
				(width 0.1)
				(type default)
			)
			(layer "F.Fab")
		)
		(fp_line
			(start -0.67945 0.3048)
			(end -0.67945 -0.305054)
			(stroke
				(width 0.1)
				(type default)
			)
			(layer "F.Fab")
		)
		(pad "1" smd circle
			(at -0.40005 0 90)
			(size 0 0)
			(layers "F.Cu" "F.Mask" "F.Paste")
			(net "PVCCIN_CPU0")
		)
		(pad "2" smd circle
			(at 0.40005 0 90)
			(size 0 0)
			(layers "F.Cu" "F.Mask" "F.Paste")
			(net "GND")
		)
	)
)
